(kicad_pcb
	(version 20260206)
	(generator "pcbnew")
	(generator_version "10.0")
	(general
		(thickness 1.6)
		(legacy_teardrops no)
	)
	(paper "A4")
	(title_block
		(title "12092022_DA0F0TMDCD0_F0T_Management_Board_D_brd_V3_OCP.brd")
		(comment 1 "Grand Teton / footprints 1440-1440 of 1440")
	)
	(layers
		(0 "F.Cu" signal "TOP")
		(4 "In1.Cu" signal "GND")
		(6 "In2.Cu" signal "IN1")
		(8 "In3.Cu" signal "GND1")
		(10 "In4.Cu" signal "IN2")
		(12 "In5.Cu" signal "VCC")
		(14 "In6.Cu" signal "VCC1")
		(16 "In7.Cu" signal "IN3")
		(18 "In8.Cu" signal "GND2")
		(20 "In9.Cu" signal "IN4")
		(22 "In10.Cu" signal "GND3")
		(2 "B.Cu" signal "BOTTOM")
		(9 "F.Adhes" user "F.Adhesive")
		(11 "B.Adhes" user "B.Adhesive")
		(13 "F.Paste" user "Package Geometry/Pastemask Top")
		(15 "B.Paste" user "Package Geometry/Pastemask Bottom")
		(5 "F.SilkS" user "Ref Des/Silkscreen Top")
		(7 "B.SilkS" user "Ref Des/Silkscreen Bottom")
		(1 "F.Mask" user "Board Geometry/Soldermask Top")
		(3 "B.Mask" user "Board Geometry/Soldermask Bottom")
		(17 "Dwgs.User" user "User.Drawings")
		(19 "Cmts.User" user "User.Comments")
		(21 "Eco1.User" user "User.Eco1")
		(23 "Eco2.User" user "User.Eco2")
		(25 "Edge.Cuts" user "Board Geometry/Outline")
		(27 "Margin" user)
		(31 "F.CrtYd" user "Package Geometry/Place Bound Top")
		(29 "B.CrtYd" user "Package Geometry/Place Bound Bottom")
		(35 "F.Fab" user "Ref Des/Assembly Top")
		(33 "B.Fab" user "Ref Des/Assembly Bottom")
	)
	(footprint ""
		(layer "B.Cu")
		(at 78.723744 -37.559488 90)
		(property "Reference" "R359"
			(at 0 0 90)
			(layer "B.SilkS")
			(hide yes)
			(effects
				(font
					(size 1.27 1.27)
				)
				(justify mirror)
			)
		)
		(property "Value" ""
			(at 0 0 90)
			(layer "B.Fab")
			(effects
				(font
					(size 1.27 1.27)
				)
				(justify mirror)
			)
		)
		(duplicate_pad_numbers_are_jumpers no)
		(fp_line
			(start 0.7874 -0.4064)
			(end -0.7874 -0.4064)
			(stroke
				(width 0.1524)
				(type default)
			)
			(layer "B.SilkS")
		)
		(fp_line
			(start -0.7874 -0.4064)
			(end -0.7874 0.4064)
			(stroke
				(width 0.1524)
				(type default)
			)
			(layer "B.SilkS")
		)
		(fp_line
			(start 0.7874 0.4064)
			(end 0.7874 -0.4064)
			(stroke
				(width 0.1524)
				(type default)
			)
			(layer "B.SilkS")
		)
		(fp_line
			(start -0.7874 0.4064)
			(end 0.7874 0.4064)
			(stroke
				(width 0.1524)
				(type default)
			)
			(layer "B.SilkS")
		)
		(fp_line
			(start 0.67945 -0.305054)
			(end 0.12065 -0.305054)
			(stroke
				(width 0.1)
				(type default)
			)
			(layer "B.Fab")
		)
		(fp_line
			(start 0.12065 -0.305054)
			(end 0.12065 -0.2794)
			(stroke
				(width 0.1)
				(type default)
			)
			(layer "B.Fab")
		)
		(fp_line
			(start -0.12065 -0.3048)
			(end -0.67945 -0.3048)
			(stroke
				(width 0.1)
				(type default)
			)
			(layer "B.Fab")
		)
		(fp_line
			(start -0.67945 -0.3048)
			(end -0.67945 0.3048)
			(stroke
				(width 0.1)
				(type default)
			)
			(layer "B.Fab")
		)
		(fp_line
			(start 0.12065 -0.2794)
			(end -0.12065 -0.2794)
			(stroke
				(width 0.1)
				(type default)
			)
			(layer "B.Fab")
		)
		(fp_line
			(start -0.12065 -0.2794)
			(end -0.12065 -0.3048)
			(stroke
				(width 0.1)
				(type default)
			)
			(layer "B.Fab")
		)
		(fp_line
			(start 0.12065 0.2794)
			(end 0.12065 0.3048)
			(stroke
				(width 0.1)
				(type default)
			)
			(layer "B.Fab")
		)
		(fp_line
			(start -0.120396 0.2794)
			(end 0.12065 0.2794)
			(stroke
				(width 0.1)
				(type default)
			)
			(layer "B.Fab")
		)
		(fp_line
			(start 0.67945 0.3048)
			(end 0.67945 -0.305054)
			(stroke
				(width 0.1)
				(type default)
			)
			(layer "B.Fab")
		)
		(fp_line
			(start 0.12065 0.3048)
			(end 0.67945 0.3048)
			(stroke
				(width 0.1)
				(type default)
			)
			(layer "B.Fab")
		)
		(fp_line
			(start -0.120396 0.3048)
			(end -0.120396 0.2794)
			(stroke
				(width 0.1)
				(type default)
			)
			(layer "B.Fab")
		)
		(fp_line
			(start -0.67945 0.3048)
			(end -0.120396 0.3048)
			(stroke
				(width 0.1)
				(type default)
			)
			(layer "B.Fab")
		)
		(pad "1" smd circle
			(at 0.40005 0 270)
			(size 0 0)
			(layers "B.Cu" "B.Mask" "B.Paste")
			(net "M_BMC_DDR4_MA<8>")
		)
		(pad "2" smd circle
			(at -0.40005 0 270)
			(size 0 0)
			(layers "B.Cu" "B.Mask" "B.Paste")
			(net "P1V2_AUX")
		)
	)
)
